(kicad_pcb
	(version 20221018)
	(generator pcbnew)
	(general
    (thickness 0.908)
  )
	(paper "A4")
	(title_block
    (title "HDMI-MIPI Bridge")
    (date "2024-04-24")
    (rev "1.3.2")
		(comment 9 "footprints 11-18 of 121")
	)
	(layers
    (0 "F.Cu" signal)
    (1 "In1.Cu" signal)
    (2 "In2.Cu" signal)
    (31 "B.Cu" signal)
    (32 "B.Adhes" user "B.Adhesive")
    (33 "F.Adhes" user "F.Adhesive")
    (34 "B.Paste" user)
    (35 "F.Paste" user)
    (36 "B.SilkS" user "B.Silkscreen")
    (37 "F.SilkS" user "F.Silkscreen")
    (38 "B.Mask" user)
    (39 "F.Mask" user)
    (40 "Dwgs.User" user "User.Drawings")
    (41 "Cmts.User" user "User.Comments")
    (42 "Eco1.User" user "User.Eco1")
    (43 "Eco2.User" user "User.Eco2")
    (44 "Edge.Cuts" user)
    (45 "Margin" user)
    (46 "B.CrtYd" user "B.Courtyard")
    (47 "F.CrtYd" user "F.Courtyard")
    (48 "B.Fab" user)
    (49 "F.Fab" user)
  )
	(footprint "antmicro-footprints:OSHW-Logo_7.5x8mm_Mask"
		(layer "F.Cu")
    (at 178 123.3 -90)
    (descr "Open Source Hardware Logo")
    (tags "Logo OSHW")
    (property "Author" "Antmicro")
    (property "License" "Apache-2.0")
    (property "MPN" "")
    (property "Manufacturer" "")
    (property "Public" "False")
    (property "Sheetfile" "antmicro-hdmi-mipi-bridge-hw.kicad_sch")
    (property "Sheetname" "")
    (property "exclude_from_bom" "")
    (property "ki_description" "Mechanical part")
    (attr exclude_from_pos_files exclude_from_bom)
    (fp_text reference "N2" (at 0 0 90) (layer "F.SilkS") hide
        (effects (font (size 1 1) (thickness 0.15)))
    )
    (fp_text value "oshw_logo" (at 0.75 0 90) (layer "F.Fab") hide
        (effects (font (size 1 1) (thickness 0.15)))
    )
  )
	(footprint "antmicro-footprints:C_0402_1005Metric" (layer "F.Cu")
    (at 139.3 114.3 180)
    (descr "Capacitor SMD 0402")
    (tags "capacitor SMD 0402")
    (property "Author" "Antmicro")
    (property "Dielectric" "X5R")
    (property "License" "Apache-2.0")
    (property "MPN" "GRM155R61H104KE14D")
    (property "Manufacturer" "Murata")
    (property "Public" "False")
    (property "Sheetfile" "channel1.kicad_sch")
    (property "Sheetname" "Channel 1")
    (property "Val" "100n")
    (property "Voltage" "50V")
    (property "ki_description" "SMD Multilayer Ceramic Capacitor, 0.1 µF, 50 V, 0402 [1005 Metric], ± 10%, X5R, GRM Series")
    (property "ki_keywords" "0402, SMT, CAPACITOR, PASSIVE, CERAMIC, MLCC")
    (attr smd)
    (fp_text reference "C27" (at 1.8 -5.6) (layer "F.SilkS")
        (effects (font (size 0.65 0.65) (thickness 0.13)) (justify right bottom))
    )
    (fp_text value "C_100n_0402" (at 0 1.4) (layer "F.Fab")
        (effects (font (size 0.65 0.65) (thickness 0.13)) (justify right bottom))
    )
    (fp_text user "${REFERENCE}" (at -0.932 3.168) (layer "F.Fab") hide
        (effects (font (size 0.7 0.7) (thickness 0.15)) (justify right bottom))
    )
    (fp_text user "License: Apache-2.0" (at -0.932 5.17) (layer "F.Fab") hide
        (effects (font (size 0.7 0.7) (thickness 0.15)) (justify right bottom))
    )
    (fp_text user "Author: Antmicro" (at -0.932 4.17) (layer "F.Fab") hide
        (effects (font (size 0.7 0.7) (thickness 0.15)) (justify right bottom))
    )
    (fp_rect (start -0.925 -0.47) (end 0.925 0.47)
      (stroke (width 0.05) (type default)) (fill none) (layer "F.CrtYd"))
    (fp_line (start -0.494 -0.25) (end 0.504 -0.25)
      (stroke (width 0.15) (type solid)) (layer "F.Fab"))
    (fp_line (start -0.494 0.248) (end -0.494 -0.25)
      (stroke (width 0.15) (type solid)) (layer "F.Fab"))
    (fp_line (start 0.504 -0.25) (end 0.504 0.248)
      (stroke (width 0.15) (type solid)) (layer "F.Fab"))
    (fp_line (start 0.504 0.248) (end -0.494 0.248)
      (stroke (width 0.15) (type solid)) (layer "F.Fab"))
    (pad "1" smd roundrect (at -0.48 0 180) (size 0.59 0.64) (layers "F.Cu" "F.Paste" "F.Mask") (roundrect_rratio 0.25)
      (net 2 "GND") (pintype "passive"))
    (pad "2" smd roundrect (at 0.48 0 180) (size 0.59 0.64) (layers "F.Cu" "F.Paste" "F.Mask") (roundrect_rratio 0.25)
      (net 19 "Net-(C27-Pad2)") (pintype "passive"))
  )
	(footprint "antmicro-footprints:C_0402_1005Metric" (layer "F.Cu")
    (at 123 105.4 -90)
    (descr "Capacitor SMD 0402")
    (tags "capacitor SMD 0402")
    (property "Author" "Antmicro")
    (property "Dielectric" "C0G")
    (property "License" "Apache-2.0")
    (property "MPN" "C0402C470J5GACTU")
    (property "Manufacturer" "KEMET")
    (property "Public" "False")
    (property "Sheetfile" "channel1.kicad_sch")
    (property "Sheetname" "Channel 1")
    (property "Val" "47p")
    (property "Voltage" "")
    (property "ki_description" "SMD Multilayer Ceramic Capacitor, 47 pF, 50 V, 0402 [1005 Metric], ± 5%, C0G / NP0, C Series KEMET")
    (property "ki_keywords" "0402, SMT, CAPACITOR, PASSIVE, CERAMIC, MLCC")
    (attr smd)
    (fp_text reference "C13" (at -3 -0.3 90) (layer "F.SilkS")
        (effects (font (size 0.65 0.65) (thickness 0.13)) (justify right bottom))
    )
    (fp_text value "C_47p_0402" (at 0 1.4 90) (layer "F.Fab")
        (effects (font (size 0.65 0.65) (thickness 0.13)) (justify right bottom))
    )
    (fp_text user "Author: Antmicro" (at -0.932 4.17 90) (layer "F.Fab") hide
        (effects (font (size 0.7 0.7) (thickness 0.15)) (justify right bottom))
    )
    (fp_text user "${REFERENCE}" (at -0.932 3.168 90) (layer "F.Fab") hide
        (effects (font (size 0.7 0.7) (thickness 0.15)) (justify right bottom))
    )
    (fp_text user "License: Apache-2.0" (at -0.932 5.17 90) (layer "F.Fab") hide
        (effects (font (size 0.7 0.7) (thickness 0.15)) (justify right bottom))
    )
    (fp_rect (start -0.925 -0.47) (end 0.925 0.47)
      (stroke (width 0.05) (type default)) (fill none) (layer "F.CrtYd"))
    (fp_line (start -0.494 -0.25) (end 0.504 -0.25)
      (stroke (width 0.15) (type solid)) (layer "F.Fab"))
    (fp_line (start -0.494 0.248) (end -0.494 -0.25)
      (stroke (width 0.15) (type solid)) (layer "F.Fab"))
    (fp_line (start 0.504 -0.25) (end 0.504 0.248)
      (stroke (width 0.15) (type solid)) (layer "F.Fab"))
    (fp_line (start 0.504 0.248) (end -0.494 0.248)
      (stroke (width 0.15) (type solid)) (layer "F.Fab"))
    (pad "1" smd roundrect (at -0.48 0 270) (size 0.59 0.64) (layers "F.Cu" "F.Paste" "F.Mask") (roundrect_rratio 0.25)
      (net 2 "GND") (pintype "passive"))
    (pad "2" smd roundrect (at 0.48 0 270) (size 0.59 0.64) (layers "F.Cu" "F.Paste" "F.Mask") (roundrect_rratio 0.25)
      (net 9 "+3V3") (pintype "passive"))
  )
	(footprint "antmicro-footprints:FB_0805_2012Metric" (layer "F.Cu")
    (at 129.4 105.4 180)
    (descr "FERRITE BEAD 0805")
    (tags "FERRITE BEAD 0805")
    (property "Author" "Antmicro")
    (property "Current" "")
    (property "License" "Apache-2.0")
    (property "MPN" "742792096")
    (property "Manufacturer" "Würth Elektronik")
    (property "Public" "False")
    (property "Sheetfile" "channel1.kicad_sch")
    (property "Sheetname" "Channel 1")
    (property "Val" "1kZ/0.8A")
    (property "ki_description" "Ferrite Beads WE-CBF 0805 100MHz 1kOhm 1A, High Current")
    (property "ki_keywords" "FERRITE BEAD, PASSIVE")
    (attr smd)
    (fp_text reference "FB5" (at -0.5 1) (layer "F.SilkS")
        (effects (font (size 0.65 0.65) (thickness 0.13)) (justify right bottom))
    )
    (fp_text value "FB_1kZ_0.8A_WE-CBF_0805" (at 0 1.8) (layer "F.Fab")
        (effects (font (size 0.65 0.65) (thickness 0.13)) (justify right bottom))
    )
    (fp_text user "License: Apache-2.0" (at -1.9 5.75) (layer "F.Fab") hide
        (effects (font (size 0.7 0.7) (thickness 0.15)) (justify right bottom))
    )
    (fp_text user "Author: Antmicro" (at -1.9 4.4) (layer "F.Fab") hide
        (effects (font (size 0.7 0.7) (thickness 0.15)) (justify right bottom))
    )
    (fp_text user "${REFERENCE}" (at -1.9 3.1) (layer "F.Fab") hide
        (effects (font (size 0.7 0.7) (thickness 0.15)) (justify right bottom))
    )
    (fp_line (start -0.319 0.698) (end 0.281 0.698)
      (stroke (width 0.15) (type solid)) (layer "F.SilkS"))
    (fp_line (start -0.299 -0.698) (end 0.299 -0.698)
      (stroke (width 0.15) (type solid)) (layer "F.SilkS"))
    (fp_rect (start 1.95 -0.9) (end -1.95 0.9)
      (stroke (width 0.05) (type default)) (fill none) (layer "F.CrtYd"))
    (fp_line (start -0.948 -0.681) (end 0.948 -0.681)
      (stroke (width 0.15) (type solid)) (layer "F.Fab"))
    (fp_line (start -0.948 -0.676) (end -0.948 0.676)
      (stroke (width 0.15) (type solid)) (layer "F.Fab"))
    (fp_line (start -0.948 0.681) (end 0.948 0.681)
      (stroke (width 0.15) (type solid)) (layer "F.Fab"))
    (fp_line (start 0.948 -0.676) (end 0.948 0.676)
      (stroke (width 0.15) (type solid)) (layer "F.Fab"))
    (pad "1" smd roundrect (at -1.1 0 180) (size 1.2 1.3) (layers "F.Cu" "F.Paste" "F.Mask") (roundrect_rratio 0.25)
      (net 8 "Net-(U1B-VDDC1)") (pintype "passive"))
    (pad "2" smd roundrect (at 1.1 0 180) (size 1.2 1.3) (layers "F.Cu" "F.Paste" "F.Mask") (roundrect_rratio 0.25)
      (net 12 "CH1_1V2") (pintype "passive"))
  )
	(footprint "antmicro-footprints:SOT-23-5" (layer "F.Cu")
    (at 168.15 119.1 90)
    (property "Author" "Antmicro")
    (property "License" "Apache-2.0")
    (property "MPN" "TLV73312PDBVT")
    (property "Manufacturer" "Texas Instruments")
    (property "Sheetfile" "channel2.kicad_sch")
    (property "Sheetname" "Channel 2")
    (property "ki_description" "Fixed LDO Voltage Regulator, 1.4V to 5.5V, 122mV Dropout, 1.2Vout, 300mAout, SOT-23-5")
    (property "ki_keywords" "SMT, PMIC, IC, LDO, LINEAR, VOLTAGE, REGULATOR")
    (attr smd)
    (fp_text reference "IC4" (at -3.02 -0.93 180) (layer "F.SilkS")
        (effects (font (size 0.65 0.65) (thickness 0.13)) (justify left bottom))
    )
    (fp_text value "TLV73312PDBVT" (at 0.002 2.799 90) (layer "F.Fab")
        (effects (font (size 0.65 0.65) (thickness 0.13)) (justify left bottom))
    )
    (fp_text user "License: Apache-2.0" (at -1.898 6.7 90) (layer "F.Fab") hide
        (effects (font (size 0.7 0.7) (thickness 0.15)) (justify left bottom))
    )
    (fp_text user "Author: Antmicro" (at -1.898 5.499 90) (layer "F.Fab") hide
        (effects (font (size 0.7 0.7) (thickness 0.15)) (justify left bottom))
    )
    (fp_text user "${REFERENCE}" (at -1.898 4.299 90) (layer "F.Fab") hide
        (effects (font (size 0.7 0.7) (thickness 0.15)) (justify left bottom))
    )
    (fp_line (start -0.85 1.6) (end -0.85 1.301)
      (stroke (width 0.15) (type solid)) (layer "F.SilkS"))
    (fp_line (start -0.8 -1.6) (end -0.8 -1.3)
      (stroke (width 0.15) (type solid)) (layer "F.SilkS"))
    (fp_line (start -0.8 -1.6) (end -0.5 -1.6)
      (stroke (width 0.15) (type solid)) (layer "F.SilkS"))
    (fp_line (start -0.55 1.6) (end -0.85 1.6)
      (stroke (width 0.15) (type solid)) (layer "F.SilkS"))
    (fp_line (start 0.8 -1.6) (end 0.5 -1.6)
      (stroke (width 0.15) (type solid)) (layer "F.SilkS"))
    (fp_line (start 0.8 -1.3) (end 0.8 -1.6)
      (stroke (width 0.15) (type solid)) (layer "F.SilkS"))
    (fp_line (start 0.8 0.55) (end 0.8 -0.55)
      (stroke (width 0.15) (type solid)) (layer "F.SilkS"))
    (fp_line (start 0.8 1.3) (end 0.8 1.599)
      (stroke (width 0.15) (type solid)) (layer "F.SilkS"))
    (fp_line (start 0.8 1.599) (end 0.549 1.599)
      (stroke (width 0.15) (type solid)) (layer "F.SilkS"))
    (fp_circle (center -1.25 -1.5) (end -1.2 -1.5)
      (stroke (width 0.15) (type solid)) (fill solid) (layer "F.SilkS"))
    (fp_rect (start 1.9 -1.76) (end -1.9 1.75)
      (stroke (width 0.05) (type solid)) (fill none) (layer "F.CrtYd"))
    (fp_line (start -0.398 -1.526) (end -0.874 -1.05)
      (stroke (width 0.15) (type solid)) (layer "F.Fab"))
    (fp_rect (start 0.874 1.523) (end -0.873 -1.525)
      (stroke (width 0.15) (type solid)) (fill none) (layer "F.Fab"))
    (pad "1" smd rect (at -1.351 -0.951) (size 0.55 1) (layers "F.Cu" "F.Paste" "F.Mask")
      (net 9 "+3V3") (pinfunction "VIN") (pintype "power_in"))
    (pad "2" smd rect (at -1.351 0) (size 0.55 1) (layers "F.Cu" "F.Paste" "F.Mask")
      (net 2 "GND") (pinfunction "GND") (pintype "power_in"))
    (pad "3" smd rect (at -1.351 0.949) (size 0.55 1) (layers "F.Cu" "F.Paste" "F.Mask")
      (net 9 "+3V3") (pinfunction "EN") (pintype "input"))
    (pad "4" smd rect (at 1.35 0.949) (size 0.55 1) (layers "F.Cu" "F.Paste" "F.Mask")
      (net 103 "unconnected-(IC4-NC-Pad4)") (pinfunction "NC") (pintype "no_connect"))
    (pad "5" smd rect (at 1.35 -0.951) (size 0.55 1) (layers "F.Cu" "F.Paste" "F.Mask")
      (net 25 "CH2_1V2") (pinfunction "VOUT") (pintype "power_out"))
  )
	(footprint "antmicro-footprints:FB_0805_2012Metric" (layer "F.Cu")
    (at 142.6 112.6 -90)
    (descr "FERRITE BEAD 0805")
    (tags "FERRITE BEAD 0805")
    (property "Author" "Antmicro")
    (property "Current" "")
    (property "License" "Apache-2.0")
    (property "MPN" "742792096")
    (property "Manufacturer" "Würth Elektronik")
    (property "Public" "False")
    (property "Sheetfile" "channel1.kicad_sch")
    (property "Sheetname" "Channel 1")
    (property "Val" "1kZ/0.8A")
    (property "ki_description" "Ferrite Beads WE-CBF 0805 100MHz 1kOhm 1A, High Current")
    (property "ki_keywords" "FERRITE BEAD, PASSIVE")
    (attr smd)
    (fp_text reference "FB2" (at -0.98 -1.79 90) (layer "F.SilkS")
        (effects (font (size 0.65 0.65) (thickness 0.13)) (justify right bottom))
    )
    (fp_text value "FB_1kZ_0.8A_WE-CBF_0805" (at 0 1.8 90) (layer "F.Fab")
        (effects (font (size 0.65 0.65) (thickness 0.13)) (justify right bottom))
    )
    (fp_text user "License: Apache-2.0" (at -1.9 5.75 90) (layer "F.Fab") hide
        (effects (font (size 0.7 0.7) (thickness 0.15)) (justify right bottom))
    )
    (fp_text user "Author: Antmicro" (at -1.9 4.4 90) (layer "F.Fab") hide
        (effects (font (size 0.7 0.7) (thickness 0.15)) (justify right bottom))
    )
    (fp_text user "${REFERENCE}" (at -1.9 3.1 90) (layer "F.Fab") hide
        (effects (font (size 0.7 0.7) (thickness 0.15)) (justify right bottom))
    )
    (fp_line (start -0.319 0.698) (end 0.281 0.698)
      (stroke (width 0.15) (type solid)) (layer "F.SilkS"))
    (fp_line (start -0.299 -0.698) (end 0.299 -0.698)
      (stroke (width 0.15) (type solid)) (layer "F.SilkS"))
    (fp_rect (start 1.95 -0.9) (end -1.95 0.9)
      (stroke (width 0.05) (type default)) (fill none) (layer "F.CrtYd"))
    (fp_line (start -0.948 -0.681) (end 0.948 -0.681)
      (stroke (width 0.15) (type solid)) (layer "F.Fab"))
    (fp_line (start -0.948 -0.676) (end -0.948 0.676)
      (stroke (width 0.15) (type solid)) (layer "F.Fab"))
    (fp_line (start -0.948 0.681) (end 0.948 0.681)
      (stroke (width 0.15) (type solid)) (layer "F.Fab"))
    (fp_line (start 0.948 -0.676) (end 0.948 0.676)
      (stroke (width 0.15) (type solid)) (layer "F.Fab"))
    (pad "1" smd roundrect (at -1.1 0 270) (size 1.2 1.3) (layers "F.Cu" "F.Paste" "F.Mask") (roundrect_rratio 0.25)
      (net 5 "Net-(U1B-AVDD25)") (pintype "passive"))
    (pad "2" smd roundrect (at 1.1 0 270) (size 1.2 1.3) (layers "F.Cu" "F.Paste" "F.Mask") (roundrect_rratio 0.25)
      (net 11 "CH1_2V5") (pintype "passive"))
  )
	(footprint "antmicro-footprints:C_0402_1005Metric" (layer "F.Cu")
    (at 124 110.2 90)
    (descr "Capacitor SMD 0402")
    (tags "capacitor SMD 0402")
    (property "Author" "Antmicro")
    (property "Dielectric" "C0G")
    (property "License" "Apache-2.0")
    (property "MPN" "C0402C470J5GACTU")
    (property "Manufacturer" "KEMET")
    (property "Public" "False")
    (property "Sheetfile" "channel1.kicad_sch")
    (property "Sheetname" "Channel 1")
    (property "Val" "47p")
    (property "Voltage" "")
    (property "ki_description" "SMD Multilayer Ceramic Capacitor, 47 pF, 50 V, 0402 [1005 Metric], ± 5%, C0G / NP0, C Series KEMET")
    (property "ki_keywords" "0402, SMT, CAPACITOR, PASSIVE, CERAMIC, MLCC")
    (attr smd)
    (fp_text reference "C16" (at -3.2 0.4 90) (layer "F.SilkS")
        (effects (font (size 0.65 0.65) (thickness 0.13)) (justify left bottom))
    )
    (fp_text value "C_47p_0402" (at 0 1.4 90) (layer "F.Fab")
        (effects (font (size 0.65 0.65) (thickness 0.13)) (justify left bottom))
    )
    (fp_text user "Author: Antmicro" (at -0.932 4.17 90) (layer "F.Fab") hide
        (effects (font (size 0.7 0.7) (thickness 0.15)) (justify left bottom))
    )
    (fp_text user "${REFERENCE}" (at -0.932 3.168 90) (layer "F.Fab") hide
        (effects (font (size 0.7 0.7) (thickness 0.15)) (justify left bottom))
    )
    (fp_text user "License: Apache-2.0" (at -0.932 5.17 90) (layer "F.Fab") hide
        (effects (font (size 0.7 0.7) (thickness 0.15)) (justify left bottom))
    )
    (fp_rect (start -0.925 -0.47) (end 0.925 0.47)
      (stroke (width 0.05) (type default)) (fill none) (layer "F.CrtYd"))
    (fp_line (start -0.494 -0.25) (end 0.504 -0.25)
      (stroke (width 0.15) (type solid)) (layer "F.Fab"))
    (fp_line (start -0.494 0.248) (end -0.494 -0.25)
      (stroke (width 0.15) (type solid)) (layer "F.Fab"))
    (fp_line (start 0.504 -0.25) (end 0.504 0.248)
      (stroke (width 0.15) (type solid)) (layer "F.Fab"))
    (fp_line (start 0.504 0.248) (end -0.494 0.248)
      (stroke (width 0.15) (type solid)) (layer "F.Fab"))
    (pad "1" smd roundrect (at -0.48 0 90) (size 0.59 0.64) (layers "F.Cu" "F.Paste" "F.Mask") (roundrect_rratio 0.25)
      (net 2 "GND") (pintype "passive"))
    (pad "2" smd roundrect (at 0.48 0 90) (size 0.59 0.64) (layers "F.Cu" "F.Paste" "F.Mask") (roundrect_rratio 0.25)
      (net 10 "Net-(Y1-EN)") (pintype "passive"))
  )
	(footprint "antmicro-footprints:C_0402_1005Metric" (layer "F.Cu")
    (at 163.295 114.35 180)
    (descr "Capacitor SMD 0402")
    (tags "capacitor SMD 0402")
    (property "Author" "Antmicro")
    (property "Dielectric" "X5R")
    (property "License" "Apache-2.0")
    (property "MPN" "GRM155R61H104KE14D")
    (property "Manufacturer" "Murata")
    (property "Public" "False")
    (property "Sheetfile" "channel2.kicad_sch")
    (property "Sheetname" "Channel 2")
    (property "Val" "100n")
    (property "Voltage" "50V")
    (property "ki_description" "SMD Multilayer Ceramic Capacitor, 0.1 µF, 50 V, 0402 [1005 Metric], ± 10%, X5R, GRM Series")
    (property "ki_keywords" "0402, SMT, CAPACITOR, PASSIVE, CERAMIC, MLCC")
    (attr smd)
    (fp_text reference "C31" (at 1.695 -6.65) (layer "F.SilkS")
        (effects (font (size 0.65 0.65) (thickness 0.13)) (justify right bottom))
    )
    (fp_text value "C_100n_0402" (at 0 1.4) (layer "F.Fab")
        (effects (font (size 0.65 0.65) (thickness 0.13)) (justify right bottom))
    )
    (fp_text user "License: Apache-2.0" (at -0.932 5.17) (layer "F.Fab") hide
        (effects (font (size 0.7 0.7) (thickness 0.15)) (justify right bottom))
    )
    (fp_text user "Author: Antmicro" (at -0.932 4.17) (layer "F.Fab") hide
        (effects (font (size 0.7 0.7) (thickness 0.15)) (justify right bottom))
    )
    (fp_text user "${REFERENCE}" (at -0.932 3.168) (layer "F.Fab") hide
        (effects (font (size 0.7 0.7) (thickness 0.15)) (justify right bottom))
    )
    (fp_rect (start -0.925 -0.47) (end 0.925 0.47)
      (stroke (width 0.05) (type default)) (fill none) (layer "F.CrtYd"))
    (fp_line (start -0.494 -0.25) (end 0.504 -0.25)
      (stroke (width 0.15) (type solid)) (layer "F.Fab"))
    (fp_line (start -0.494 0.248) (end -0.494 -0.25)
      (stroke (width 0.15) (type solid)) (layer "F.Fab"))
    (fp_line (start 0.504 -0.25) (end 0.504 0.248)
      (stroke (width 0.15) (type solid)) (layer "F.Fab"))
    (fp_line (start 0.504 0.248) (end -0.494 0.248)
      (stroke (width 0.15) (type solid)) (layer "F.Fab"))
    (pad "1" smd roundrect (at -0.48 0 180) (size 0.59 0.64) (layers "F.Cu" "F.Paste" "F.Mask") (roundrect_rratio 0.25)
      (net 2 "GND") (pintype "passive"))
    (pad "2" smd roundrect (at 0.48 0 180) (size 0.59 0.64) (layers "F.Cu" "F.Paste" "F.Mask") (roundrect_rratio 0.25)
      (net 22 "Net-(C31-Pad2)") (pintype "passive"))
  )
)
